(kicad_pcb
	(version 20241229)
	(generator "pcbnew")
	(generator_version "9.0")
	(general
		(thickness 1.552)
		(legacy_teardrops no)
	)
	(paper "A4")
	(title_block
		(date "2023-07-25")
		(rev "1.1.4")
		(comment 9 "footprint 195 of 379 (U12), pads 88-96 of 96")
	)
	(layers
		(0 "F.Cu" signal)
		(4 "In1.Cu" signal)
		(6 "In2.Cu" signal)
		(8 "In3.Cu" signal)
		(10 "In4.Cu" signal)
		(12 "In5.Cu" signal)
		(14 "In6.Cu" signal)
		(2 "B.Cu" signal)
		(9 "F.Adhes" user "F.Adhesive")
		(11 "B.Adhes" user "B.Adhesive")
		(13 "F.Paste" user)
		(15 "B.Paste" user)
		(5 "F.SilkS" user "F.Silkscreen")
		(7 "B.SilkS" user "B.Silkscreen")
		(1 "F.Mask" user)
		(3 "B.Mask" user)
		(17 "Dwgs.User" user "User.Drawings")
		(19 "Cmts.User" user "User.Comments")
		(21 "Eco1.User" user "User.Eco1")
		(23 "Eco2.User" user "User.Eco2")
		(25 "Edge.Cuts" user)
		(27 "Margin" user)
		(31 "F.CrtYd" user "F.Courtyard")
		(29 "B.CrtYd" user "B.Courtyard")
		(35 "F.Fab" user)
		(33 "B.Fab" user)
	)
	(footprint "antmicro-footprints:BGA-96-48_8x14mm_Layout16x9_P0.8mm"
		(layer "F.Cu")
		(at 124.26 65.34 180)
		(property "Reference" "U12"
			(at 0 -8.1 180)
			(layer "F.SilkS")
			(effects
				(font
					(size 0.7 0.7)
					(thickness 0.15)
				)
				(justify left bottom)
			)
		)
		(property "Value" "MT41K128M16JT-125_K"
			(at 0 8.4 180)
			(layer "F.Fab")
			(effects
				(font
					(size 0.7 0.7)
					(thickness 0.15)
				)
				(justify left bottom)
			)
		)
		(property "Datasheet" "https://www.mouser.com/datasheet/2/671/mict_s_a0002296722_1-2290882.pdf"
			(at 0 0 180)
			(layer "F.Fab")
			(hide yes)
			(effects
				(font
					(size 1.27 1.27)
					(thickness 0.15)
				)
			)
		)
		(property "Description" "SDRAM - DDR3L Memory IC 2Gbit Parallel 800 MHz 13.75 ns 96-FBGA (8x14)"
			(at 0 0 180)
			(layer "F.Fab")
			(hide yes)
			(effects
				(font
					(size 1.27 1.27)
					(thickness 0.15)
				)
			)
		)
		(property "Author" "Antmicro"
			(at 248.52 130.68 0)
			(layer "F.Fab")
			(hide yes)
			(effects
				(font
					(size 1 1)
					(thickness 0.15)
				)
			)
		)
		(property "License" "Apache-2.0"
			(at 248.52 130.68 0)
			(layer "F.Fab")
			(hide yes)
			(effects
				(font
					(size 1 1)
					(thickness 0.15)
				)
			)
		)
		(property "MPN" "MT41K128M16JT-125:K"
			(at 248.52 130.68 0)
			(layer "F.Fab")
			(hide yes)
			(effects
				(font
					(size 1 1)
					(thickness 0.15)
				)
			)
		)
		(property "Manufacturer" "Micron Technology"
			(at 248.52 130.68 0)
			(layer "F.Fab")
			(hide yes)
			(effects
				(font
					(size 1 1)
					(thickness 0.15)
				)
			)
		)
		(sheetname "/DDR3/")
		(sheetfile "ddr3.kicad_sch")
		(attr smd)
		(pad "R7" smd circle
			(at 1.6 5.2 180)
			(size 0.35 0.35)
			(layers "F.Cu" "F.Mask" "F.Paste")
			(net 154 "/DDR3/DDR3_A11")
			(pinfunction "A11")
			(pintype "input")
		)
		(pad "R8" smd circle
			(at 2.399 5.2 180)
			(size 0.35 0.35)
			(layers "F.Cu" "F.Mask" "F.Paste")
			(net 148 "/DDR3/DDR3_A6")
			(pinfunction "A6")
			(pintype "input")
		)
		(pad "R9" smd circle
			(at 3.2 5.2 180)
			(size 0.35 0.35)
			(layers "F.Cu" "F.Mask" "F.Paste")
			(net 248 "+1V5")
			(pinfunction "VDD")
			(pintype "passive")
		)
		(pad "T1" smd circle
			(at -3.201 5.999 180)
			(size 0.35 0.35)
			(layers "F.Cu" "F.Mask" "F.Paste")
			(net 1 "GND")
			(pinfunction "VSS")
			(pintype "passive")
		)
		(pad "T2" smd circle
			(at -2.4 5.999 180)
			(size 0.35 0.35)
			(layers "F.Cu" "F.Mask" "F.Paste")
			(net 164 "/DDR3/~{DDR3_RESET}")
			(pinfunction "~{RESET}")
			(pintype "input")
		)
		(pad "T3" smd circle
			(at -1.601 5.999 180)
			(size 0.35 0.35)
			(layers "F.Cu" "F.Mask" "F.Paste")
			(net 158 "/DDR3/DDR3_A13")
			(pinfunction "A13")
			(pintype "input")
		)
		(pad "T7" smd circle
			(at 1.6 5.999 180)
			(size 0.35 0.35)
			(layers "F.Cu" "F.Mask" "F.Paste")
			(net 319 "unconnected-(U12-PadT7)")
			(pinfunction "T7")
			(pintype "no_connect")
		)
		(pad "T8" smd circle
			(at 2.399 5.999 180)
			(size 0.35 0.35)
			(layers "F.Cu" "F.Mask" "F.Paste")
			(net 155 "/DDR3/DDR3_A8")
			(pinfunction "A8")
			(pintype "input")
		)
		(pad "T9" smd circle
			(at 3.2 5.999 180)
			(size 0.35 0.35)
			(layers "F.Cu" "F.Mask" "F.Paste")
			(net 1 "GND")
			(pinfunction "VSS")
			(pintype "passive")
		)
	)
)
